# BASEBOARD_FAB2 (Tioga Pass) — schematic netlist excerpt (pin names and nets, part order shuffled) for the footprints in the layout excerpt that follows; sources: Cadence DE-HDL packaged netlist, KiCad conversion of Wiwynn_Tioga_Pass_MB.brd

R12W9  RES  100.0K 1% CHIP  pkg 0603  page 197 : A = P12V_NVDIMM_DEF ; B = PWRGD_PVDDQ_DEF_N
C3M18  CAP  10UF 4V 20% X6S  pkg 0603LF  page 127 : A = P1V05_PCH_STBY_VCCA_PLL0 ; B = GND
R1U4  RES  100.0K 1% CHIP  pkg 0402  page 147 : A = FAN_TACH1 ; B = GND

(kicad_pcb
	(version 20260206)
	(generator "pcbnew")
	(generator_version "10.0")
	(general
		(thickness 1.6)
		(legacy_teardrops no)
	)
	(paper "A4")
	(title_block
		(title "Wiwynn_Tioga_Pass_MB.brd")
		(comment 1 "Tioga Pass / footprints 3956-3958 of 4770")
	)
	(layers
		(0 "F.Cu" signal "TOP")
		(4 "In1.Cu" signal "L2GND")
		(6 "In2.Cu" signal "L3")
		(8 "In3.Cu" signal "L4GND")
		(10 "In4.Cu" signal "L5")
		(12 "In5.Cu" signal "L6GND")
		(14 "In6.Cu" signal "L7VCC")
		(16 "In7.Cu" signal "L8VCC")
		(18 "In8.Cu" signal "L9GND")
		(20 "In9.Cu" signal "L10")
		(22 "In10.Cu" signal "L11GND")
		(24 "In11.Cu" signal "L12")
		(26 "In12.Cu" signal "L13GND")
		(2 "B.Cu" signal "BOTTOM")
		(9 "F.Adhes" user "F.Adhesive")
		(11 "B.Adhes" user "B.Adhesive")
		(13 "F.Paste" user "Package Geometry/Pastemask Top")
		(15 "B.Paste" user "Package Geometry/Pastemask Bottom")
		(5 "F.SilkS" user "Ref Des/Silkscreen Top")
		(7 "B.SilkS" user "Ref Des/Silkscreen Bottom")
		(1 "F.Mask" user "Board Geometry/Soldermask Top")
		(3 "B.Mask" user "Board Geometry/Soldermask Bottom")
		(17 "Dwgs.User" user "User.Drawings")
		(19 "Cmts.User" user "User.Comments")
		(21 "Eco1.User" user "User.Eco1")
		(23 "Eco2.User" user "User.Eco2")
		(25 "Edge.Cuts" user "Board Geometry/Outline")
		(27 "Margin" user)
		(31 "F.CrtYd" user "Package Geometry/Place Bound Top")
		(29 "B.CrtYd" user "Package Geometry/Place Bound Bottom")
		(35 "F.Fab" user "Ref Des/Assembly Top")
		(33 "B.Fab" user "Ref Des/Assembly Bottom")
	)
	(footprint ""
		(layer "B.Cu")
		(at 185.2549 -127.3048 180)
		(property "Reference" "R12W9"
			(at -1.01473 0.656336 270)
			(unlocked yes)
			(layer "B.SilkS")
			(effects
				(font
					(size 0.4064 0.254)
					(thickness 0.1524)
				)
				(justify mirror)
			)
		)
		(property "Value" ""
			(at 0 0 0)
			(layer "B.Fab")
			(effects
				(font
					(size 1.27 1.27)
				)
				(justify mirror)
			)
		)
		(duplicate_pad_numbers_are_jumpers no)
		(fp_poly
			(pts
				(xy 0.4953 -0.2032) (xy -0.4953 -0.2032) (xy -0.4953 1.6002) (xy 0.4953 1.6002)
			)
			(stroke
				(width 0)
				(type default)
			)
			(fill no)
			(layer "B.CrtYd")
		)
		(fp_line
			(start 0.4953 1.6002)
			(end 0.4953 -0.2032)
			(stroke
				(width 0.1)
				(type default)
			)
			(layer "B.Fab")
		)
		(fp_line
			(start 0.4953 -0.2032)
			(end -0.4953 -0.2032)
			(stroke
				(width 0.1)
				(type default)
			)
			(layer "B.Fab")
		)
		(fp_line
			(start -0.4953 1.6002)
			(end 0.4953 1.6002)
			(stroke
				(width 0.1)
				(type default)
			)
			(layer "B.Fab")
		)
		(fp_line
			(start -0.4953 -0.2032)
			(end -0.4953 1.6002)
			(stroke
				(width 0.1)
				(type default)
			)
			(layer "B.Fab")
		)
		(pad "1" smd rect
			(at 0 0)
			(size 0.762 0.889)
			(layers "B.Cu" "B.Mask" "B.Paste")
			(net "P12V_NVDIMM_DEF")
		)
		(pad "2" smd rect
			(at 0 1.397)
			(size 0.762 0.889)
			(layers "B.Cu" "B.Mask" "B.Paste")
			(net "PWRGD_PVDDQ_DEF_N")
		)
		(zone
			(layer "B.Cu")
			(hatch none 0.5)
			(connect_pads
				(clearance 0)
			)
			(min_thickness 0.25)
			(keepout
				(tracks not_allowed)
				(vias allowed)
				(pads allowed)
				(copperpour not_allowed)
				(footprints allowed)
			)
			(placement
				(enabled no)
				(sheetname "")
			)
			(fill
				(thermal_gap 0.5)
				(thermal_bridge_width 0.5)
				(island_removal_mode 0)
			)
			(polygon
				(pts
					(xy 184.8739 -128.2573) (xy 184.8739 -127.7493) (xy 185.6359 -127.7493) (xy 185.6359 -128.2573)
				)
			)
		)
		(zone
			(layer "B.Cu")
			(hatch none 0.5)
			(connect_pads
				(clearance 0)
			)
			(min_thickness 0.25)
			(keepout
				(tracks allowed)
				(vias not_allowed)
				(pads allowed)
				(copperpour not_allowed)
				(footprints allowed)
			)
			(placement
				(enabled no)
				(sheetname "")
			)
			(fill
				(thermal_gap 0.5)
				(thermal_bridge_width 0.5)
				(island_removal_mode 0)
			)
			(polygon
				(pts
					(xy 185.6359 -128.2573) (xy 185.6359 -127.7493) (xy 184.8739 -127.7493) (xy 184.8739 -128.2573)
				)
			)
		)
	)
	(footprint ""
		(layer "B.Cu")
		(at 427.4185 -23.368 90)
		(property "Reference" "R1U4"
			(at 0 0 90)
			(layer "B.SilkS")
			(hide yes)
			(effects
				(font
					(size 1.27 1.27)
				)
				(justify mirror)
			)
		)
		(property "Value" ""
			(at 0 0 90)
			(layer "B.Fab")
			(effects
				(font
					(size 1.27 1.27)
				)
				(justify mirror)
			)
		)
		(duplicate_pad_numbers_are_jumpers no)
		(fp_poly
			(pts
				(xy 0.2794 -0.1016) (xy -0.2794 -0.1016) (xy -0.2794 0.9906) (xy 0.2794 0.9906)
			)
			(stroke
				(width 0)
				(type default)
			)
			(fill no)
			(layer "B.CrtYd")
		)
		(fp_line
			(start 0.2794 -0.1016)
			(end 0.2794 0.9906)
			(stroke
				(width 0.1)
				(type default)
			)
			(layer "B.Fab")
		)
		(fp_line
			(start -0.2794 -0.1016)
			(end 0.2794 -0.1016)
			(stroke
				(width 0.1)
				(type default)
			)
			(layer "B.Fab")
		)
		(fp_line
			(start 0.2794 0.9906)
			(end -0.2794 0.9906)
			(stroke
				(width 0.1)
				(type default)
			)
			(layer "B.Fab")
		)
		(fp_line
			(start -0.2794 0.9906)
			(end -0.2794 -0.1016)
			(stroke
				(width 0.1)
				(type default)
			)
			(layer "B.Fab")
		)
		(pad "1" smd rect
			(at 0 0 270)
			(size 0.508 0.508)
			(layers "B.Cu" "B.Mask" "B.Paste")
			(net "FAN_TACH1")
		)
		(pad "2" smd rect
			(at 0 0.889 270)
			(size 0.508 0.508)
			(layers "B.Cu" "B.Mask" "B.Paste")
			(net "GND")
		)
		(zone
			(layer "B.Cu")
			(hatch none 0.5)
			(connect_pads
				(clearance 0)
			)
			(min_thickness 0.25)
			(keepout
				(tracks allowed)
				(vias not_allowed)
				(pads allowed)
				(copperpour not_allowed)
				(footprints allowed)
			)
			(placement
				(enabled no)
				(sheetname "")
			)
			(fill
				(thermal_gap 0.5)
				(thermal_bridge_width 0.5)
				(island_removal_mode 0)
			)
			(polygon
				(pts
					(xy 427.6725 -23.622) (xy 427.6725 -23.114) (xy 428.0535 -23.114) (xy 428.0535 -23.622)
				)
			)
		)
		(zone
			(layer "B.Cu")
			(hatch none 0.5)
			(connect_pads
				(clearance 0)
			)
			(min_thickness 0.25)
			(keepout
				(tracks not_allowed)
				(vias allowed)
				(pads allowed)
				(copperpour not_allowed)
				(footprints allowed)
			)
			(placement
				(enabled no)
				(sheetname "")
			)
			(fill
				(thermal_gap 0.5)
				(thermal_bridge_width 0.5)
				(island_removal_mode 0)
			)
			(polygon
				(pts
					(xy 428.0535 -23.622) (xy 428.0535 -23.114) (xy 427.6725 -23.114) (xy 427.6725 -23.622)
				)
			)
		)
	)
	(footprint ""
		(layer "B.Cu")
		(at 372.4275 -138.049 -90)
		(property "Reference" "C3M18"
			(at 0 0 90)
			(layer "B.SilkS")
			(hide yes)
			(effects
				(font
					(size 1.27 1.27)
				)
				(justify mirror)
			)
		)
		(property "Value" ""
			(at 0 0 90)
			(layer "B.Fab")
			(effects
				(font
					(size 1.27 1.27)
				)
				(justify mirror)
			)
		)
		(duplicate_pad_numbers_are_jumpers no)
		(fp_poly
			(pts
				(xy 0.4953 -0.2032) (xy -0.4953 -0.2032) (xy -0.4953 1.6002) (xy 0.4953 1.6002)
			)
			(stroke
				(width 0)
				(type default)
			)
			(fill no)
			(layer "B.CrtYd")
		)
		(fp_line
			(start -0.4953 1.6002)
			(end 0.4953 1.6002)
			(stroke
				(width 0.1)
				(type default)
			)
			(layer "B.Fab")
		)
		(fp_line
			(start 0.4953 1.6002)
			(end 0.4953 -0.2032)
			(stroke
				(width 0.1)
				(type default)
			)
			(layer "B.Fab")
		)
		(fp_line
			(start -0.4953 -0.2032)
			(end -0.4953 1.6002)
			(stroke
				(width 0.1)
				(type default)
			)
			(layer "B.Fab")
		)
		(fp_line
			(start 0.4953 -0.2032)
			(end -0.4953 -0.2032)
			(stroke
				(width 0.1)
				(type default)
			)
			(layer "B.Fab")
		)
		(pad "1" smd rect
			(at 0 0 90)
			(size 0.762 0.889)
			(layers "B.Cu" "B.Mask" "B.Paste")
			(net "P1V05_PCH_STBY_VCCA_PLL0")
		)
		(pad "2" smd rect
			(at 0 1.397 90)
			(size 0.762 0.889)
			(layers "B.Cu" "B.Mask" "B.Paste")
			(net "GND")
		)
		(zone
			(layer "B.Cu")
			(hatch none 0.5)
			(connect_pads
				(clearance 0)
			)
			(min_thickness 0.25)
			(keepout
				(tracks not_allowed)
				(vias allowed)
				(pads allowed)
				(copperpour not_allowed)
				(footprints allowed)
			)
			(placement
				(enabled no)
				(sheetname "")
			)
			(fill
				(thermal_gap 0.5)
				(thermal_bridge_width 0.5)
				(island_removal_mode 0)
			)
			(polygon
				(pts
					(xy 371.983 -137.668) (xy 371.983 -138.43) (xy 371.475 -138.43) (xy 371.475 -137.668)
				)
			)
		)
	)
)
